# S9S_MB_2U (Grand Teton) — schematic netlist excerpt (pin names and nets, part order shuffled) for the footprints in the layout excerpt that follows; sources: Cadence DE-HDL packaged netlist, KiCad conversion of 03242023_DA0F0TMBIJ0_F0T_Motherboard_J_brd_V01_OCP.brd

PU9_P0_5  ISL99390FRZTR5935  ISL99390FRZ-TR5935 IC  pkg QFN21_6X5XB  page 269
  VOS  = PVCCIN_CPU0_VOS5
  AGND  = GND
  VCC  = PVCCIN_CPU0_VDD5
  PVCC  = PVCCIN_CPU0_PVCC
  PGND1  = GND
  GL1  = NC
  PGND2  = GND
  SW  = SW_PVCCIN_CPU0_SW5
  VIN1  = SW_P12V_PVCCIN_CPU0_FLT
  VIN2  = SW_P12V_PVCCIN_CPU0_FLT
  DNC  = NC
  PHASE  = SW_PVCCIN_CPU0_BOOTR5
  BOOT  = SW_PVCCIN_CPU0_BOOT5
  PWM  = PVCCIN_CPU0_PWM5
  EN  = PVCCIN_CPU0_VDD5
  TOUT_FLT  = PVCCIN_CPU0_ATSEN
  LSET  = PVCCIN_CPU0_LSET5
  IOUT  = PVCCIN_CPU0_IMON5
  REFIN  = PVCCIN_CPU0_VREF
  PGND3  = GND
  GL2  = NC

(kicad_pcb
	(version 20260206)
	(generator "pcbnew")
	(generator_version "10.0")
	(general
		(thickness 1.6)
		(legacy_teardrops no)
	)
	(paper "A4")
	(title_block
		(title "03242023_DA0F0TMBIJ0_F0T_Motherboard_J_brd_V01_OCP.brd")
		(comment 1 "Grand Teton / footprints 384-384 of 6105")
	)
	(layers
		(0 "F.Cu" signal "TOP")
		(4 "In1.Cu" signal "GND")
		(6 "In2.Cu" signal "IN1")
		(8 "In3.Cu" signal "GND1")
		(10 "In4.Cu" signal "IN2")
		(12 "In5.Cu" signal "GND2")
		(14 "In6.Cu" signal "IN3")
		(16 "In7.Cu" signal "GND3")
		(18 "In8.Cu" signal "VCC")
		(20 "In9.Cu" signal "VCC1")
		(22 "In10.Cu" signal "GND4")
		(24 "In11.Cu" signal "IN4")
		(26 "In12.Cu" signal "GND5")
		(28 "In13.Cu" signal "IN5")
		(30 "In14.Cu" signal "GND6")
		(32 "In15.Cu" signal "IN6")
		(34 "In16.Cu" signal "GND7")
		(2 "B.Cu" signal "BOTTOM")
		(9 "F.Adhes" user "F.Adhesive")
		(11 "B.Adhes" user "B.Adhesive")
		(13 "F.Paste" user "Package Geometry/Pastemask Top")
		(15 "B.Paste" user "Package Geometry/Pastemask Bottom")
		(5 "F.SilkS" user "Ref Des/Silkscreen Top")
		(7 "B.SilkS" user "Ref Des/Silkscreen Bottom")
		(1 "F.Mask" user "Board Geometry/Soldermask Top")
		(3 "B.Mask" user "Board Geometry/Soldermask Bottom")
		(17 "Dwgs.User" user "User.Drawings")
		(19 "Cmts.User" user "User.Comments")
		(21 "Eco1.User" user "User.Eco1")
		(23 "Eco2.User" user "User.Eco2")
		(25 "Edge.Cuts" user "Board Geometry/Outline")
		(27 "Margin" user)
		(31 "F.CrtYd" user "Package Geometry/Place Bound Top")
		(29 "B.CrtYd" user "Package Geometry/Place Bound Bottom")
		(35 "F.Fab" user "Ref Des/Assembly Top")
		(33 "B.Fab" user "Ref Des/Assembly Bottom")
	)
	(footprint ""
		(layer "F.Cu")
		(at 377.579636 -337.126326)
		(property "Reference" "PU9_P0_5"
			(at -3.567176 -7.230872 0)
			(unlocked yes)
			(layer "F.SilkS")
			(effects
				(font
					(size 0.7874 0.5842)
					(thickness 0.1524)
				)
				(justify left)
			)
		)
		(property "Value" ""
			(at 0 0 0)
			(layer "F.Fab")
			(effects
				(font
					(size 1.27 1.27)
				)
			)
		)
		(duplicate_pad_numbers_are_jumpers no)
		(fp_line
			(start -2.500122 -2.999994)
			(end -2.24409 -2.999994)
			(stroke
				(width 0.1524)
				(type default)
			)
			(layer "F.SilkS")
		)
		(fp_line
			(start -2.500122 -2.529078)
			(end -2.500122 -2.999994)
			(stroke
				(width 0.1524)
				(type default)
			)
			(layer "F.SilkS")
		)
		(fp_line
			(start -2.500122 0.6604)
			(end -2.500122 0.229108)
			(stroke
				(width 0.1524)
				(type default)
			)
			(layer "F.SilkS")
		)
		(fp_line
			(start -2.500122 2.999994)
			(end -2.500122 2.339594)
			(stroke
				(width 0.1524)
				(type default)
			)
			(layer "F.SilkS")
		)
		(fp_line
			(start -2.2987 2.999994)
			(end -2.500122 2.999994)
			(stroke
				(width 0.1524)
				(type default)
			)
			(layer "F.SilkS")
		)
		(fp_line
			(start 2.31394 -2.999994)
			(end 2.500122 -2.999994)
			(stroke
				(width 0.1524)
				(type default)
			)
			(layer "F.SilkS")
		)
		(fp_line
			(start 2.500122 -2.999994)
			(end 2.500122 -2.44348)
			(stroke
				(width 0.1524)
				(type default)
			)
			(layer "F.SilkS")
		)
		(fp_line
			(start 2.500122 2.339594)
			(end 2.500122 2.999994)
			(stroke
				(width 0.1524)
				(type default)
			)
			(layer "F.SilkS")
		)
		(fp_line
			(start 2.500122 2.999994)
			(end 2.2987 2.999994)
			(stroke
				(width 0.1524)
				(type default)
			)
			(layer "F.SilkS")
		)
		(fp_poly
			(pts
				(xy -2.21234 -3.631438) (xy -2.72034 -2.615438) (xy -3.22834 -3.631438)
			)
			(stroke
				(width 0)
				(type default)
			)
			(fill yes)
			(layer "F.SilkS")
		)
		(fp_line
			(start -2.500122 -2.999994)
			(end 2.500122 -2.999994)
			(stroke
				(width 0.1)
				(type default)
			)
			(layer "F.Fab")
		)
		(fp_line
			(start -2.500122 2.999994)
			(end -2.500122 -2.999994)
			(stroke
				(width 0.1)
				(type default)
			)
			(layer "F.Fab")
		)
		(fp_line
			(start 2.500122 -2.999994)
			(end 2.500122 2.999994)
			(stroke
				(width 0.1)
				(type default)
			)
			(layer "F.Fab")
		)
		(fp_line
			(start 2.500122 2.999994)
			(end -2.500122 2.999994)
			(stroke
				(width 0.1)
				(type default)
			)
			(layer "F.Fab")
		)
		(fp_poly
			(pts
				(xy -4.218432 -2.783078) (xy -4.218432 -1.767078) (xy -3.202432 -2.275078)
			)
			(stroke
				(width 0)
				(type default)
			)
			(fill yes)
			(layer "F.Fab")
		)
		(pad "1" smd rect
			(at -2.400046 -2.275078 90)
			(size 0.2286 0.6096)
			(layers "F.Cu" "F.Mask" "F.Paste")
			(net "PVCCIN_CPU0_VOS5")
		)
		(pad "2" smd rect
			(at -2.400046 -1.82499 90)
			(size 0.2286 0.6096)
			(layers "F.Cu" "F.Mask" "F.Paste")
			(net "GND")
		)
		(pad "3" smd rect
			(at -2.400046 -1.374902 90)
			(size 0.2286 0.6096)
			(layers "F.Cu" "F.Mask" "F.Paste")
			(net "PVCCIN_CPU0_VDD5")
		)
		(pad "4" smd rect
			(at -2.400046 -0.925068 90)
			(size 0.2286 0.6096)
			(layers "F.Cu" "F.Mask" "F.Paste")
			(net "PVCCIN_CPU0_PVCC")
		)
		(pad "5" smd rect
			(at -2.400046 -0.47498 90)
			(size 0.2286 0.6096)
			(layers "F.Cu" "F.Mask" "F.Paste")
			(net "GND")
		)
		(pad "6" smd rect
			(at -2.400046 -0.024892 90)
			(size 0.2286 0.6096)
			(layers "F.Cu" "F.Mask" "F.Paste")
			(net "Net_8556")
		)
		(pad "7_9-20_24" smd circle
			(at 0 1.150112 90)
			(size 0 0)
			(layers "F.Cu" "F.Mask" "F.Paste")
			(net "GND")
		)
		(pad "10_19" smd rect
			(at 0 2.899918 90)
			(size 0.6096 4.318)
			(layers "F.Cu" "F.Mask" "F.Paste")
			(net "SW_PVCCIN_CPU0_SW5")
		)
		(pad "25_29" smd rect
			(at 1.549908 -1.279906 270)
			(size 2.0574 2.3114)
			(layers "F.Cu" "F.Mask" "F.Paste")
			(net "SW_P12V_PVCCIN_CPU0_FLT")
		)
		(pad "30" smd rect
			(at 2.05994 -2.899918)
			(size 0.2286 0.6096)
			(layers "F.Cu" "F.Mask" "F.Paste")
			(net "SW_P12V_PVCCIN_CPU0_FLT")
		)
		(pad "31" smd rect
			(at 1.610106 -2.899918)
			(size 0.2286 0.6096)
			(layers "F.Cu" "F.Mask" "F.Paste")
			(net "Net_8557")
		)
		(pad "32" smd rect
			(at 1.160018 -2.899918)
			(size 0.2286 0.6096)
			(layers "F.Cu" "F.Mask" "F.Paste")
			(net "SW_PVCCIN_CPU0_BOOTR5")
		)
		(pad "33" smd rect
			(at 0.70993 -2.899918)
			(size 0.2286 0.6096)
			(layers "F.Cu" "F.Mask" "F.Paste")
			(net "SW_PVCCIN_CPU0_BOOT5")
		)
		(pad "34" smd rect
			(at 0.260096 -2.899918)
			(size 0.2286 0.6096)
			(layers "F.Cu" "F.Mask" "F.Paste")
			(net "PVCCIN_CPU0_PWM5")
		)
		(pad "35" smd rect
			(at -0.189992 -2.899918)
			(size 0.2286 0.6096)
			(layers "F.Cu" "F.Mask" "F.Paste")
			(net "PVCCIN_CPU0_VDD5")
		)
		(pad "36" smd rect
			(at -0.64008 -2.899918)
			(size 0.2286 0.6096)
			(layers "F.Cu" "F.Mask" "F.Paste")
			(net "PVCCIN_CPU0_ATSEN")
		)
		(pad "37" smd rect
			(at -1.089914 -2.899918)
			(size 0.2286 0.6096)
			(layers "F.Cu" "F.Mask" "F.Paste")
			(net "PVCCIN_CPU0_LSET5")
		)
		(pad "38" smd rect
			(at -1.540002 -2.899918)
			(size 0.2286 0.6096)
			(layers "F.Cu" "F.Mask" "F.Paste")
			(net "PVCCIN_CPU0_IMON5")
		)
		(pad "39" smd rect
			(at -1.99009 -2.899918)
			(size 0.2286 0.6096)
			(layers "F.Cu" "F.Mask" "F.Paste")
			(net "PVCCIN_CPU0_VREF")
		)
		(pad "40" smd rect
			(at -0.87503 -1.27508)
			(size 1.7526 1.9558)
			(layers "F.Cu" "F.Mask" "F.Paste")
			(net "GND")
		)
		(pad "41" smd rect
			(at -1.525016 0.249936 270)
			(size 0.3048 0.4572)
			(layers "F.Cu" "F.Mask" "F.Paste")
			(net "Net_8555")
		)
		(zone
			(layer "F.Cu")
			(hatch none 0.5)
			(connect_pads
				(clearance 0)
			)
			(min_thickness 0.25)
			(keepout
				(tracks not_allowed)
				(vias allowed)
				(pads allowed)
				(copperpour not_allowed)
				(footprints allowed)
			)
			(placement
				(enabled no)
				(sheetname "")
			)
			(fill
				(thermal_gap 0.5)
				(thermal_bridge_width 0.5)
				(island_removal_mode 0)
			)
			(polygon
				(pts
					(xy 375.079514 -334.126332) (xy 375.079514 -334.875632) (xy 380.079758 -334.875632) (xy 380.079758 -334.126332)
					(xy 379.789436 -334.126332) (xy 379.789436 -334.582008) (xy 375.369836 -334.582008) (xy 375.369836 -334.126332)
				)
			)
		)
		(zone
			(layer "F.Cu")
			(hatch none 0.5)
			(connect_pads
				(clearance 0)
			)
			(min_thickness 0.25)
			(keepout
				(tracks not_allowed)
				(vias allowed)
				(pads allowed)
				(copperpour not_allowed)
				(footprints allowed)
			)
			(placement
				(enabled no)
				(sheetname "")
			)
			(fill
				(thermal_gap 0.5)
				(thermal_bridge_width 0.5)
				(island_removal_mode 0)
			)
			(polygon
				(pts
					(xy 375.53519 -337.429348) (xy 375.777506 -337.429348) (xy 375.777506 -337.372706) (xy 376.46356 -337.372706)
					(xy 376.46356 -337.058508) (xy 376.628914 -337.058508) (xy 376.628914 -336.377026) (xy 375.079514 -336.377026)
					(xy 375.079514 -336.833718) (xy 375.77522 -336.833718) (xy 375.77522 -336.67319) (xy 376.33402 -336.67319)
					(xy 376.33402 -337.07959) (xy 375.77522 -337.07959) (xy 375.77522 -336.859118) (xy 375.079514 -336.859118)
					(xy 375.079514 -336.986118) (xy 375.53519 -336.986118)
				)
			)
		)
	)
)
